# T6G (Grand Teton) — schematic netlist excerpt (pin names and nets, part order shuffled) for the footprints in the layout excerpt that follows; sources: Cadence DE-HDL packaged netlist, KiCad conversion of 04192023_DAF0TMB3IC0_F0TG_MB_C_brd_V02_OCP.brd

C1757  Q_CAP  0.1UF 25V 10% X7R  pkg 0402  page 257 : A = P3V3_MAX11617_VDD ; B = GND
PC2202  Q_CAP  100NF 50V 10% X7R  pkg C0402  page 147 : A = P12V_E1S_IMON_0 ; B = GND

(kicad_pcb
	(version 20260206)
	(generator "pcbnew")
	(generator_version "10.0")
	(general
		(thickness 1.6)
		(legacy_teardrops no)
	)
	(paper "A4")
	(title_block
		(title "04192023_DAF0TMB3IC0_F0TG_MB_C_brd_V02_OCP.brd")
		(comment 1 "Grand Teton / footprints 249-250 of 8354")
	)
	(layers
		(0 "F.Cu" signal "TOP")
		(4 "In1.Cu" signal "GND")
		(6 "In2.Cu" signal "IN1")
		(8 "In3.Cu" signal "GND1")
		(10 "In4.Cu" signal "IN2")
		(12 "In5.Cu" signal "GND2")
		(14 "In6.Cu" signal "IN3")
		(16 "In7.Cu" signal "GND3")
		(18 "In8.Cu" signal "VCC")
		(20 "In9.Cu" signal "VCC1")
		(22 "In10.Cu" signal "GND4")
		(24 "In11.Cu" signal "IN4")
		(26 "In12.Cu" signal "GND5")
		(28 "In13.Cu" signal "IN5")
		(30 "In14.Cu" signal "GND6")
		(32 "In15.Cu" signal "IN6")
		(34 "In16.Cu" signal "GND7")
		(2 "B.Cu" signal "BOTTOM")
		(9 "F.Adhes" user "F.Adhesive")
		(11 "B.Adhes" user "B.Adhesive")
		(13 "F.Paste" user "Package Geometry/Pastemask Top")
		(15 "B.Paste" user "Package Geometry/Pastemask Bottom")
		(5 "F.SilkS" user "Ref Des/Silkscreen Top")
		(7 "B.SilkS" user "Ref Des/Silkscreen Bottom")
		(1 "F.Mask" user "Board Geometry/Soldermask Top")
		(3 "B.Mask" user "Board Geometry/Soldermask Bottom")
		(17 "Dwgs.User" user "User.Drawings")
		(19 "Cmts.User" user "User.Comments")
		(21 "Eco1.User" user "User.Eco1")
		(23 "Eco2.User" user "User.Eco2")
		(25 "Edge.Cuts" user "Board Geometry/Outline")
		(27 "Margin" user)
		(31 "F.CrtYd" user "Package Geometry/Place Bound Top")
		(29 "B.CrtYd" user "Package Geometry/Place Bound Bottom")
		(35 "F.Fab" user "Ref Des/Assembly Top")
		(33 "B.Fab" user "Ref Des/Assembly Bottom")
	)
	(footprint ""
		(layer "F.Cu")
		(at 257.85953 -54.463442)
		(property "Reference" "PC2202"
			(at 0 0 0)
			(layer "F.SilkS")
			(hide yes)
			(effects
				(font
					(size 1.27 1.27)
				)
			)
		)
		(property "Value" ""
			(at 0 0 0)
			(layer "F.Fab")
			(effects
				(font
					(size 1.27 1.27)
				)
			)
		)
		(duplicate_pad_numbers_are_jumpers no)
		(fp_line
			(start -0.7874 -0.4064)
			(end 0.7874 -0.4064)
			(stroke
				(width 0.1524)
				(type default)
			)
			(layer "F.SilkS")
		)
		(fp_line
			(start -0.7874 0.4064)
			(end -0.7874 -0.4064)
			(stroke
				(width 0.1524)
				(type default)
			)
			(layer "F.SilkS")
		)
		(fp_line
			(start 0.7874 -0.4064)
			(end 0.7874 0.4064)
			(stroke
				(width 0.1524)
				(type default)
			)
			(layer "F.SilkS")
		)
		(fp_line
			(start 0.7874 0.4064)
			(end -0.7874 0.4064)
			(stroke
				(width 0.1524)
				(type default)
			)
			(layer "F.SilkS")
		)
		(fp_line
			(start -0.67945 -0.305054)
			(end -0.12065 -0.305054)
			(stroke
				(width 0.1)
				(type default)
			)
			(layer "F.Fab")
		)
		(fp_line
			(start -0.67945 0.3048)
			(end -0.67945 -0.305054)
			(stroke
				(width 0.1)
				(type default)
			)
			(layer "F.Fab")
		)
		(fp_line
			(start -0.12065 -0.305054)
			(end -0.12065 -0.2794)
			(stroke
				(width 0.1)
				(type default)
			)
			(layer "F.Fab")
		)
		(fp_line
			(start -0.12065 -0.2794)
			(end 0.12065 -0.2794)
			(stroke
				(width 0.1)
				(type default)
			)
			(layer "F.Fab")
		)
		(fp_line
			(start -0.12065 0.2794)
			(end -0.12065 0.3048)
			(stroke
				(width 0.1)
				(type default)
			)
			(layer "F.Fab")
		)
		(fp_line
			(start -0.12065 0.3048)
			(end -0.67945 0.3048)
			(stroke
				(width 0.1)
				(type default)
			)
			(layer "F.Fab")
		)
		(fp_line
			(start 0.120396 0.2794)
			(end -0.12065 0.2794)
			(stroke
				(width 0.1)
				(type default)
			)
			(layer "F.Fab")
		)
		(fp_line
			(start 0.120396 0.3048)
			(end 0.120396 0.2794)
			(stroke
				(width 0.1)
				(type default)
			)
			(layer "F.Fab")
		)
		(fp_line
			(start 0.12065 -0.3048)
			(end 0.67945 -0.3048)
			(stroke
				(width 0.1)
				(type default)
			)
			(layer "F.Fab")
		)
		(fp_line
			(start 0.12065 -0.2794)
			(end 0.12065 -0.3048)
			(stroke
				(width 0.1)
				(type default)
			)
			(layer "F.Fab")
		)
		(fp_line
			(start 0.67945 -0.3048)
			(end 0.67945 0.3048)
			(stroke
				(width 0.1)
				(type default)
			)
			(layer "F.Fab")
		)
		(fp_line
			(start 0.67945 0.3048)
			(end 0.120396 0.3048)
			(stroke
				(width 0.1)
				(type default)
			)
			(layer "F.Fab")
		)
		(pad "1" smd circle
			(at -0.40005 0)
			(size 0 0)
			(layers "F.Cu" "F.Mask" "F.Paste")
			(net "P12V_E1S_IMON_0")
		)
		(pad "2" smd circle
			(at 0.40005 0)
			(size 0 0)
			(layers "F.Cu" "F.Mask" "F.Paste")
			(net "GND")
		)
	)
	(footprint ""
		(layer "F.Cu")
		(at 329.360022 -37.017706)
		(property "Reference" "C1757"
			(at 0 0 0)
			(layer "F.SilkS")
			(hide yes)
			(effects
				(font
					(size 1.27 1.27)
				)
			)
		)
		(property "Value" ""
			(at 0 0 0)
			(layer "F.Fab")
			(effects
				(font
					(size 1.27 1.27)
				)
			)
		)
		(duplicate_pad_numbers_are_jumpers no)
		(fp_line
			(start -0.7874 -0.4064)
			(end 0.7874 -0.4064)
			(stroke
				(width 0.1524)
				(type default)
			)
			(layer "F.SilkS")
		)
		(fp_line
			(start -0.7874 0.4064)
			(end -0.7874 -0.4064)
			(stroke
				(width 0.1524)
				(type default)
			)
			(layer "F.SilkS")
		)
		(fp_line
			(start 0.7874 -0.4064)
			(end 0.7874 0.4064)
			(stroke
				(width 0.1524)
				(type default)
			)
			(layer "F.SilkS")
		)
		(fp_line
			(start 0.7874 0.4064)
			(end -0.7874 0.4064)
			(stroke
				(width 0.1524)
				(type default)
			)
			(layer "F.SilkS")
		)
		(fp_line
			(start -0.67945 -0.305054)
			(end -0.12065 -0.305054)
			(stroke
				(width 0.1)
				(type default)
			)
			(layer "F.Fab")
		)
		(fp_line
			(start -0.67945 0.3048)
			(end -0.67945 -0.305054)
			(stroke
				(width 0.1)
				(type default)
			)
			(layer "F.Fab")
		)
		(fp_line
			(start -0.12065 -0.305054)
			(end -0.12065 -0.2794)
			(stroke
				(width 0.1)
				(type default)
			)
			(layer "F.Fab")
		)
		(fp_line
			(start -0.12065 -0.2794)
			(end 0.12065 -0.2794)
			(stroke
				(width 0.1)
				(type default)
			)
			(layer "F.Fab")
		)
		(fp_line
			(start -0.12065 0.2794)
			(end -0.12065 0.3048)
			(stroke
				(width 0.1)
				(type default)
			)
			(layer "F.Fab")
		)
		(fp_line
			(start -0.12065 0.3048)
			(end -0.67945 0.3048)
			(stroke
				(width 0.1)
				(type default)
			)
			(layer "F.Fab")
		)
		(fp_line
			(start 0.120396 0.2794)
			(end -0.12065 0.2794)
			(stroke
				(width 0.1)
				(type default)
			)
			(layer "F.Fab")
		)
		(fp_line
			(start 0.120396 0.3048)
			(end 0.120396 0.2794)
			(stroke
				(width 0.1)
				(type default)
			)
			(layer "F.Fab")
		)
		(fp_line
			(start 0.12065 -0.3048)
			(end 0.67945 -0.3048)
			(stroke
				(width 0.1)
				(type default)
			)
			(layer "F.Fab")
		)
		(fp_line
			(start 0.12065 -0.2794)
			(end 0.12065 -0.3048)
			(stroke
				(width 0.1)
				(type default)
			)
			(layer "F.Fab")
		)
		(fp_line
			(start 0.67945 -0.3048)
			(end 0.67945 0.3048)
			(stroke
				(width 0.1)
				(type default)
			)
			(layer "F.Fab")
		)
		(fp_line
			(start 0.67945 0.3048)
			(end 0.120396 0.3048)
			(stroke
				(width 0.1)
				(type default)
			)
			(layer "F.Fab")
		)
		(pad "1" smd circle
			(at -0.40005 0)
			(size 0 0)
			(layers "F.Cu" "F.Mask" "F.Paste")
			(net "P3V3_MAX11617_VDD")
		)
		(pad "2" smd circle
			(at 0.40005 0)
			(size 0 0)
			(layers "F.Cu" "F.Mask" "F.Paste")
			(net "GND")
		)
	)
)
